(kicad_pcb
	(version 20260206)
	(generator "pcbnew")
	(generator_version "10.0")
	(general
		(thickness 1.6)
		(legacy_teardrops no)
	)
	(paper "A4")
	(title_block
		(title "Bryce Canyon_R.DPB_16317-1_OCP.brd")
		(comment 1 "Bryce Canyon / footprints 1382-1388 of 2099")
	)
	(layers
		(0 "F.Cu" signal "TOP")
		(4 "In1.Cu" signal "L2GND")
		(6 "In2.Cu" signal "L3")
		(8 "In3.Cu" signal "L4VCC")
		(10 "In4.Cu" signal "L5VCC")
		(12 "In5.Cu" signal "L6")
		(14 "In6.Cu" signal "L7GND")
		(2 "B.Cu" signal "BOTTOM")
		(9 "F.Adhes" user "F.Adhesive")
		(11 "B.Adhes" user "B.Adhesive")
		(13 "F.Paste" user "Package Geometry/Pastemask Top")
		(15 "B.Paste" user "Package Geometry/Pastemask Bottom")
		(5 "F.SilkS" user "Ref Des/Silkscreen Top")
		(7 "B.SilkS" user "Ref Des/Silkscreen Bottom")
		(1 "F.Mask" user "Board Geometry/Soldermask Top")
		(3 "B.Mask" user "Board Geometry/Soldermask Bottom")
		(17 "Dwgs.User" user "User.Drawings")
		(19 "Cmts.User" user "User.Comments")
		(21 "Eco1.User" user "User.Eco1")
		(23 "Eco2.User" user "User.Eco2")
		(25 "Edge.Cuts" user "Board Geometry/Outline")
		(27 "Margin" user)
		(31 "F.CrtYd" user "Package Geometry/Place Bound Top")
		(29 "B.CrtYd" user "Package Geometry/Place Bound Bottom")
		(35 "F.Fab" user "Ref Des/Assembly Top")
		(33 "B.Fab" user "Ref Des/Assembly Bottom")
	)
	(footprint ""
		(layer "F.Cu")
		(at 461.264 -99.8474 180)
		(property "Reference" "Q242"
			(at 0 0 180)
			(layer "F.SilkS")
			(hide yes)
			(effects
				(font
					(size 1.27 1.27)
				)
			)
		)
		(property "Value" "2N7002K-2-GP"
			(at 0.127 -8.9662 180)
			(unlocked yes)
			(layer "F.Fab")
			(hide yes)
			(effects
				(font
					(size 1.016 1.016)
					(thickness 0.1524)
				)
			)
		)
		(property "Device Type" "SOT23DGS2D4H44"
			(at 0.127 -10.4902 180)
			(unlocked yes)
			(layer "F.Fab")
			(hide yes)
			(effects
				(font
					(size 1.016 1.016)
					(thickness 0.1524)
				)
			)
		)
		(duplicate_pad_numbers_are_jumpers no)
		(fp_line
			(start 1.651 1.778)
			(end 1.651 -1.778)
			(stroke
				(width 0.1524)
				(type default)
			)
			(layer "F.SilkS")
		)
		(fp_line
			(start 1.651 -1.778)
			(end -1.651 -1.778)
			(stroke
				(width 0.1524)
				(type default)
			)
			(layer "F.SilkS")
		)
		(fp_line
			(start -1.651 1.778)
			(end 1.651 1.778)
			(stroke
				(width 0.1524)
				(type default)
			)
			(layer "F.SilkS")
		)
		(fp_line
			(start -1.651 -1.778)
			(end -1.651 1.778)
			(stroke
				(width 0.1524)
				(type default)
			)
			(layer "F.SilkS")
		)
		(fp_poly
			(pts
				(xy -1.778 1.8796) (xy -1.778 -1.8796) (xy 1.778 -1.8796) (xy 1.778 1.8796)
			)
			(stroke
				(width 0)
				(type default)
			)
			(fill no)
			(layer "F.CrtYd")
		)
		(fp_poly
			(pts
				(xy -1.778 1.8796) (xy -1.778 -1.8796) (xy 1.778 -1.8796) (xy 1.778 1.8796)
			)
			(stroke
				(width 0)
				(type default)
			)
			(fill no)
			(layer "F.Fab")
		)
		(pad "D" smd custom
			(at 0 -0.9525 180)
			(size 0.1905 0.1905)
			(layers "F.Cu" "F.Mask" "F.Paste")
			(net "FLT_HDD23_N")
			(options
				(clearance outline)
				(anchor circle)
			)
			(primitives
				(gr_poly
					(pts
						(arc
							(start -0.1778 0.5715)
							(mid -0.321484 0.511984)
							(end -0.381 0.3683)
						)
						(arc
							(start -0.381 -0.3683)
							(mid -0.321484 -0.511984)
							(end -0.1778 -0.5715)
						)
						(arc
							(start 0.1778 -0.5715)
							(mid 0.321484 -0.511984)
							(end 0.381 -0.3683)
						)
						(arc
							(start 0.381 0.3683)
							(mid 0.321484 0.511984)
							(end 0.1778 0.5715)
						)
					)
					(width 0)
					(fill yes)
				)
			)
		)
		(pad "G" smd custom
			(at -0.98425 0.9525 180)
			(size 0.1905 0.1905)
			(layers "F.Cu" "F.Mask" "F.Paste")
			(net "DRIVE_B_23_FLT_LED")
			(options
				(clearance outline)
				(anchor circle)
			)
			(primitives
				(gr_poly
					(pts
						(arc
							(start -0.1778 0.5715)
							(mid -0.321484 0.511984)
							(end -0.381 0.3683)
						)
						(arc
							(start -0.381 -0.3683)
							(mid -0.321484 -0.511984)
							(end -0.1778 -0.5715)
						)
						(arc
							(start 0.1778 -0.5715)
							(mid 0.321484 -0.511984)
							(end 0.381 -0.3683)
						)
						(arc
							(start 0.381 0.3683)
							(mid 0.321484 0.511984)
							(end 0.1778 0.5715)
						)
					)
					(width 0)
					(fill yes)
				)
			)
		)
		(pad "S" smd custom
			(at 0.98425 0.9525 180)
			(size 0.1905 0.1905)
			(layers "F.Cu" "F.Mask" "F.Paste")
			(net "GND")
			(options
				(clearance outline)
				(anchor circle)
			)
			(primitives
				(gr_poly
					(pts
						(arc
							(start -0.1778 0.5715)
							(mid -0.321484 0.511984)
							(end -0.381 0.3683)
						)
						(arc
							(start -0.381 -0.3683)
							(mid -0.321484 -0.511984)
							(end -0.1778 -0.5715)
						)
						(arc
							(start 0.1778 -0.5715)
							(mid 0.321484 -0.511984)
							(end 0.381 -0.3683)
						)
						(arc
							(start 0.381 0.3683)
							(mid 0.321484 0.511984)
							(end 0.1778 0.5715)
						)
					)
					(width 0)
					(fill yes)
				)
			)
		)
	)
	(footprint ""
		(layer "F.Cu")
		(at 432.689 -135.509 90)
		(property "Reference" "R569"
			(at 0 0 90)
			(layer "F.SilkS")
			(hide yes)
			(effects
				(font
					(size 1.27 1.27)
				)
			)
		)
		(property "Value" "200KR2F-L-GP"
			(at 0.064008 -3.993896 90)
			(unlocked yes)
			(layer "F.Fab")
			(hide yes)
			(effects
				(font
					(size 1.016 1.016)
					(thickness 0.1524)
				)
			)
		)
		(property "Device Type" "R402H16"
			(at 0.064008 -5.517896 90)
			(unlocked yes)
			(layer "F.Fab")
			(hide yes)
			(effects
				(font
					(size 1.016 1.016)
					(thickness 0.1524)
				)
			)
		)
		(duplicate_pad_numbers_are_jumpers no)
		(fp_line
			(start 0.508 -0.9398)
			(end -0.508 -0.9398)
			(stroke
				(width 0.1524)
				(type default)
			)
			(layer "F.SilkS")
		)
		(fp_line
			(start -0.508 -0.9398)
			(end -0.508 0.9398)
			(stroke
				(width 0.1524)
				(type default)
			)
			(layer "F.SilkS")
		)
		(fp_rect
			(start -0.508 0.9398)
			(end 0.508 -0.9398)
			(stroke
				(width 0)
				(type default)
			)
			(fill no)
			(layer "F.CrtYd")
		)
		(fp_rect
			(start -0.508 0.9398)
			(end 0.508 -0.9398)
			(stroke
				(width 0)
				(type default)
			)
			(fill no)
			(layer "F.Fab")
		)
		(pad "1" smd custom
			(at 0 -0.4445 90)
			(size 0.1397 0.1397)
			(layers "F.Cu" "F.Mask" "F.Paste")
			(net "SW_HDD_R21")
			(options
				(clearance outline)
				(anchor circle)
			)
			(primitives
				(gr_poly
					(pts
						(arc
							(start -0.1778 -0.2794)
							(mid -0.249642 -0.249642)
							(end -0.2794 -0.1778)
						)
						(arc
							(start -0.2794 0.1778)
							(mid -0.249642 0.249642)
							(end -0.1778 0.2794)
						)
						(arc
							(start 0.1778 0.2794)
							(mid 0.249642 0.249642)
							(end 0.2794 0.1778)
						)
						(arc
							(start 0.2794 -0.1778)
							(mid 0.249642 -0.249642)
							(end 0.1778 -0.2794)
						)
					)
					(width 0)
					(fill yes)
				)
			)
		)
		(pad "2" smd custom
			(at 0 0.4445 90)
			(size 0.1397 0.1397)
			(layers "F.Cu" "F.Mask" "F.Paste")
			(net "SW_HDD_N21")
			(options
				(clearance outline)
				(anchor circle)
			)
			(primitives
				(gr_poly
					(pts
						(arc
							(start -0.1778 -0.2794)
							(mid -0.249642 -0.249642)
							(end -0.2794 -0.1778)
						)
						(arc
							(start -0.2794 0.1778)
							(mid -0.249642 0.249642)
							(end -0.1778 0.2794)
						)
						(arc
							(start 0.1778 0.2794)
							(mid 0.249642 0.249642)
							(end 0.2794 0.1778)
						)
						(arc
							(start 0.2794 -0.1778)
							(mid 0.249642 -0.249642)
							(end 0.1778 -0.2794)
						)
					)
					(width 0)
					(fill yes)
				)
			)
		)
	)
	(footprint ""
		(layer "F.Cu")
		(at 352.1456 -146.6342 180)
		(property "Reference" "R507"
			(at 0 0 180)
			(layer "F.SilkS")
			(hide yes)
			(effects
				(font
					(size 1.27 1.27)
				)
			)
		)
		(property "Value" "10KR2F-2-GP"
			(at 0.064008 -3.993896 180)
			(unlocked yes)
			(layer "F.Fab")
			(hide yes)
			(effects
				(font
					(size 1.016 1.016)
					(thickness 0.1524)
				)
			)
		)
		(property "Device Type" "R402H16"
			(at 0.064008 -5.517896 180)
			(unlocked yes)
			(layer "F.Fab")
			(hide yes)
			(effects
				(font
					(size 1.016 1.016)
					(thickness 0.1524)
				)
			)
		)
		(duplicate_pad_numbers_are_jumpers no)
		(fp_line
			(start 0.508 -0.9398)
			(end -0.508 -0.9398)
			(stroke
				(width 0.1524)
				(type default)
			)
			(layer "F.SilkS")
		)
		(fp_line
			(start -0.508 -0.9398)
			(end -0.508 0.9398)
			(stroke
				(width 0.1524)
				(type default)
			)
			(layer "F.SilkS")
		)
		(fp_rect
			(start -0.508 0.9398)
			(end 0.508 -0.9398)
			(stroke
				(width 0)
				(type default)
			)
			(fill no)
			(layer "F.CrtYd")
		)
		(fp_rect
			(start -0.508 0.9398)
			(end 0.508 -0.9398)
			(stroke
				(width 0)
				(type default)
			)
			(fill no)
			(layer "F.Fab")
		)
		(pad "1" smd custom
			(at 0 -0.4445 180)
			(size 0.1397 0.1397)
			(layers "F.Cu" "F.Mask" "F.Paste")
			(net "P3V3_STBY_B")
			(options
				(clearance outline)
				(anchor circle)
			)
			(primitives
				(gr_poly
					(pts
						(arc
							(start -0.1778 -0.2794)
							(mid -0.249642 -0.249642)
							(end -0.2794 -0.1778)
						)
						(arc
							(start -0.2794 0.1778)
							(mid -0.249642 0.249642)
							(end -0.1778 0.2794)
						)
						(arc
							(start 0.1778 0.2794)
							(mid 0.249642 0.249642)
							(end 0.2794 0.1778)
						)
						(arc
							(start 0.2794 -0.1778)
							(mid 0.249642 -0.249642)
							(end 0.1778 -0.2794)
						)
					)
					(width 0)
					(fill yes)
				)
			)
		)
		(pad "2" smd custom
			(at 0 0.4445 180)
			(size 0.1397 0.1397)
			(layers "F.Cu" "F.Mask" "F.Paste")
			(net "HDD_PRSNT_19")
			(options
				(clearance outline)
				(anchor circle)
			)
			(primitives
				(gr_poly
					(pts
						(arc
							(start -0.1778 -0.2794)
							(mid -0.249642 -0.249642)
							(end -0.2794 -0.1778)
						)
						(arc
							(start -0.2794 0.1778)
							(mid -0.249642 0.249642)
							(end -0.1778 0.2794)
						)
						(arc
							(start 0.1778 0.2794)
							(mid 0.249642 0.249642)
							(end 0.2794 0.1778)
						)
						(arc
							(start 0.2794 -0.1778)
							(mid 0.249642 -0.249642)
							(end 0.1778 -0.2794)
						)
					)
					(width 0)
					(fill yes)
				)
			)
		)
	)
	(footprint ""
		(layer "F.Cu")
		(at 349.6818 -32.8676 180)
		(property "Reference" "R787"
			(at 0 0 180)
			(layer "F.SilkS")
			(hide yes)
			(effects
				(font
					(size 1.27 1.27)
				)
			)
		)
		(property "Value" "220R3F-1-GP"
			(at -0.0254 -2.5146 180)
			(unlocked yes)
			(layer "F.Fab")
			(hide yes)
			(effects
				(font
					(size 1.016 1.016)
					(thickness 0.1524)
				)
			)
		)
		(property "Device Type" "R603H22"
			(at -0.0254 -4.0386 180)
			(unlocked yes)
			(layer "F.Fab")
			(hide yes)
			(effects
				(font
					(size 1.016 1.016)
					(thickness 0.1524)
				)
			)
		)
		(duplicate_pad_numbers_are_jumpers no)
		(fp_line
			(start 0.2032 0)
			(end 0.4826 0)
			(stroke
				(width 0.2032)
				(type default)
			)
			(layer "F.SilkS")
		)
		(fp_line
			(start -0.4826 0)
			(end -0.2032 0)
			(stroke
				(width 0.2032)
				(type default)
			)
			(layer "F.SilkS")
		)
		(fp_rect
			(start -0.5842 1.3335)
			(end 0.5842 -1.3335)
			(stroke
				(width 0)
				(type default)
			)
			(fill no)
			(layer "F.CrtYd")
		)
		(fp_rect
			(start -0.5842 1.3335)
			(end 0.5842 -1.3335)
			(stroke
				(width 0)
				(type default)
			)
			(fill no)
			(layer "F.Fab")
		)
		(pad "1" smd custom
			(at 0 -0.762 180)
			(size 0.2159 0.2159)
			(layers "F.Cu" "F.Mask" "F.Paste")
			(net "HDD_PRSNT_31")
			(options
				(clearance outline)
				(anchor circle)
			)
			(primitives
				(gr_poly
					(pts
						(arc
							(start -0.3302 -0.4318)
							(mid -0.402042 -0.402042)
							(end -0.4318 -0.3302)
						)
						(arc
							(start -0.4318 0.3302)
							(mid -0.402042 0.402042)
							(end -0.3302 0.4318)
						)
						(arc
							(start 0.3302 0.4318)
							(mid 0.402042 0.402042)
							(end 0.4318 0.3302)
						)
						(arc
							(start 0.4318 -0.3302)
							(mid 0.402042 -0.402042)
							(end 0.3302 -0.4318)
						)
					)
					(width 0)
					(fill yes)
				)
			)
		)
		(pad "2" smd custom
			(at 0 0.762 180)
			(size 0.2159 0.2159)
			(layers "F.Cu" "F.Mask" "F.Paste")
			(net "DRIVE_B_31_INS")
			(options
				(clearance outline)
				(anchor circle)
			)
			(primitives
				(gr_poly
					(pts
						(arc
							(start -0.3302 -0.4318)
							(mid -0.402042 -0.402042)
							(end -0.4318 -0.3302)
						)
						(arc
							(start -0.4318 0.3302)
							(mid -0.402042 0.402042)
							(end -0.3302 0.4318)
						)
						(arc
							(start 0.3302 0.4318)
							(mid 0.402042 0.402042)
							(end 0.4318 0.3302)
						)
						(arc
							(start 0.4318 -0.3302)
							(mid 0.402042 -0.402042)
							(end 0.3302 -0.4318)
						)
					)
					(width 0)
					(fill yes)
				)
			)
		)
	)
	(footprint ""
		(layer "F.Cu")
		(at 64.0588 -248.750074 -90)
		(property "Reference" "VIA4"
			(at 0 0 270)
			(layer "F.SilkS")
			(hide yes)
			(effects
				(font
					(size 1.27 1.27)
				)
			)
		)
		(property "Value" "100OHM-8L-2D36MM-L16-GP"
			(at -3.4036 -0.4572 270)
			(unlocked yes)
			(layer "F.Fab")
			(hide yes)
			(effects
				(font
					(size 1.016 1.016)
					(thickness 0.1524)
				)
			)
		)
		(property "Device Type" "VIA-PCIE-4P-427097"
			(at -3.4036 -1.9812 270)
			(unlocked yes)
			(layer "F.Fab")
			(hide yes)
			(effects
				(font
					(size 1.016 1.016)
					(thickness 0.1524)
				)
			)
		)
		(duplicate_pad_numbers_are_jumpers no)
		(fp_rect
			(start -2.1336 0.4826)
			(end 2.1336 -0.4826)
			(stroke
				(width 0)
				(type default)
			)
			(fill no)
			(layer "F.CrtYd")
		)
		(fp_rect
			(start -2.1336 0.4826)
			(end 2.1336 -0.4826)
			(stroke
				(width 0)
				(type default)
			)
			(fill no)
			(layer "F.Fab")
		)
		(pad "1" thru_hole circle
			(at -1.651 0 270)
			(size 0.508 0.508)
			(drill 0.254)
			(layers "*.Cu" "*.Mask")
			(remove_unused_layers no)
			(net "GND")
			(clearance 0.2286)
			(thermal_gap 0.2286)
		)
		(pad "2" thru_hole circle
			(at -0.635 0 270)
			(size 0.508 0.508)
			(drill 0.254)
			(layers "*.Cu" "*.Mask")
			(remove_unused_layers no)
			(net "PHY_DRV_B_TO_SCC_B_1_DP")
			(clearance 0.2286)
			(thermal_gap 0.2286)
		)
		(pad "3" thru_hole circle
			(at 0.635 0 270)
			(size 0.508 0.508)
			(drill 0.254)
			(layers "*.Cu" "*.Mask")
			(remove_unused_layers no)
			(net "PHY_DRV_B_TO_SCC_B_1_DN")
			(clearance 0.2286)
			(thermal_gap 0.2286)
		)
		(pad "4" thru_hole circle
			(at 1.651 0 270)
			(size 0.508 0.508)
			(drill 0.254)
			(layers "*.Cu" "*.Mask")
			(remove_unused_layers no)
			(net "GND")
			(clearance 0.2286)
			(thermal_gap 0.2286)
		)
	)
	(footprint ""
		(layer "F.Cu")
		(at 174.625 -247.65 180)
		(property "Reference" "D5"
			(at 0 0 180)
			(layer "F.SilkS")
			(hide yes)
			(effects
				(font
					(size 1.27 1.27)
				)
			)
		)
		(property "Value" "RB551V30-GP"
			(at 0 -6.7818 180)
			(unlocked yes)
			(layer "F.Fab")
			(hide yes)
			(effects
				(font
					(size 1.016 1.016)
					(thickness 0.1524)
				)
			)
		)
		(property "Device Type" "SOD323AKH38"
			(at 0 -8.6868 180)
			(unlocked yes)
			(layer "F.Fab")
			(hide yes)
			(effects
				(font
					(size 1.016 1.016)
					(thickness 0.1524)
				)
			)
		)
		(duplicate_pad_numbers_are_jumpers no)
		(fp_line
			(start 0.889 2.159)
			(end -0.889 2.159)
			(stroke
				(width 0.1524)
				(type default)
			)
			(layer "F.SilkS")
		)
		(fp_line
			(start 0.889 -1.9304)
			(end 0.889 2.159)
			(stroke
				(width 0.1524)
				(type default)
			)
			(layer "F.SilkS")
		)
		(fp_line
			(start 0.762 2.0574)
			(end -0.762 2.0574)
			(stroke
				(width 0.508)
				(type default)
			)
			(layer "F.SilkS")
		)
		(fp_line
			(start -0.889 2.159)
			(end -0.889 -1.9304)
			(stroke
				(width 0.1524)
				(type default)
			)
			(layer "F.SilkS")
		)
		(fp_line
			(start -0.889 -1.9304)
			(end 0.889 -1.9304)
			(stroke
				(width 0.1524)
				(type default)
			)
			(layer "F.SilkS")
		)
		(fp_rect
			(start -1.016 2.3114)
			(end 1.016 -2.0066)
			(stroke
				(width 0)
				(type default)
			)
			(fill no)
			(layer "F.CrtYd")
		)
		(fp_poly
			(pts
				(xy -1.016 -2.0066) (xy 1.016 -2.0066) (xy 1.016 2.3114) (xy -1.016 2.3114)
			)
			(stroke
				(width 0)
				(type default)
			)
			(fill no)
			(layer "F.Fab")
		)
		(pad "A" smd rect
			(at 0 -1.143 180)
			(size 0.5588 1.016)
			(layers "F.Cu" "F.Mask" "F.Paste")
			(net "SW_HDD_R5")
		)
		(pad "K" smd rect
			(at 0 1.143 180)
			(size 0.5588 1.016)
			(layers "F.Cu" "F.Mask" "F.Paste")
			(net "SW_HDD_N5")
		)
	)
	(footprint ""
		(layer "F.Cu")
		(at 118.999 -19.177)
		(property "Reference" "R701"
			(at 0 0 0)
			(layer "F.SilkS")
			(hide yes)
			(effects
				(font
					(size 1.27 1.27)
				)
			)
		)
		(property "Value" "0R2J-2-GP"
			(at 0.064008 -3.993896 0)
			(unlocked yes)
			(layer "F.Fab")
			(hide yes)
			(effects
				(font
					(size 1.016 1.016)
					(thickness 0.1524)
				)
			)
		)
		(property "Device Type" "R402H16"
			(at 0.064008 -5.517896 0)
			(unlocked yes)
			(layer "F.Fab")
			(hide yes)
			(effects
				(font
					(size 1.016 1.016)
					(thickness 0.1524)
				)
			)
		)
		(duplicate_pad_numbers_are_jumpers no)
		(fp_line
			(start -0.508 -0.9398)
			(end -0.508 0.9398)
			(stroke
				(width 0.1524)
				(type default)
			)
			(layer "F.SilkS")
		)
		(fp_line
			(start 0.508 -0.9398)
			(end -0.508 -0.9398)
			(stroke
				(width 0.1524)
				(type default)
			)
			(layer "F.SilkS")
		)
		(fp_rect
			(start -0.508 0.9398)
			(end 0.508 -0.9398)
			(stroke
				(width 0)
				(type default)
			)
			(fill no)
			(layer "F.CrtYd")
		)
		(fp_rect
			(start -0.508 0.9398)
			(end 0.508 -0.9398)
			(stroke
				(width 0)
				(type default)
			)
			(fill no)
			(layer "F.Fab")
		)
		(pad "1" smd custom
			(at 0 -0.4445)
			(size 0.1397 0.1397)
			(layers "F.Cu" "F.Mask" "F.Paste")
			(net "DRIVE_B_27_PWR")
			(options
				(clearance outline)
				(anchor circle)
			)
			(primitives
				(gr_poly
					(pts
						(arc
							(start -0.1778 -0.2794)
							(mid -0.249642 -0.249642)
							(end -0.2794 -0.1778)
						)
						(arc
							(start -0.2794 0.1778)
							(mid -0.249642 0.249642)
							(end -0.1778 0.2794)
						)
						(arc
							(start 0.1778 0.2794)
							(mid 0.249642 0.249642)
							(end 0.2794 0.1778)
						)
						(arc
							(start 0.2794 -0.1778)
							(mid 0.249642 -0.249642)
							(end 0.1778 -0.2794)
						)
					)
					(width 0)
					(fill yes)
				)
			)
		)
		(pad "2" smd custom
			(at 0 0.4445)
			(size 0.1397 0.1397)
			(layers "F.Cu" "F.Mask" "F.Paste")
			(net "SW_PWR_R_HDD27")
			(options
				(clearance outline)
				(anchor circle)
			)
			(primitives
				(gr_poly
					(pts
						(arc
							(start -0.1778 -0.2794)
							(mid -0.249642 -0.249642)
							(end -0.2794 -0.1778)
						)
						(arc
							(start -0.2794 0.1778)
							(mid -0.249642 0.249642)
							(end -0.1778 0.2794)
						)
						(arc
							(start 0.1778 0.2794)
							(mid 0.249642 0.249642)
							(end 0.2794 0.1778)
						)
						(arc
							(start 0.2794 -0.1778)
							(mid 0.249642 -0.249642)
							(end 0.1778 -0.2794)
						)
					)
					(width 0)
					(fill yes)
				)
			)
		)
	)
)
